(kicad_pcb
	(version 20260206)
	(generator "pcbnew")
	(generator_version "10.0")
	(general
		(thickness 1.6)
		(legacy_teardrops no)
	)
	(paper "A4")
	(title_block
		(title "Wiwynn_Tioga_Pass_MB.brd")
		(comment 1 "Tioga Pass / footprints 3683-3690 of 4770")
	)
	(layers
		(0 "F.Cu" signal "TOP")
		(4 "In1.Cu" signal "L2GND")
		(6 "In2.Cu" signal "L3")
		(8 "In3.Cu" signal "L4GND")
		(10 "In4.Cu" signal "L5")
		(12 "In5.Cu" signal "L6GND")
		(14 "In6.Cu" signal "L7VCC")
		(16 "In7.Cu" signal "L8VCC")
		(18 "In8.Cu" signal "L9GND")
		(20 "In9.Cu" signal "L10")
		(22 "In10.Cu" signal "L11GND")
		(24 "In11.Cu" signal "L12")
		(26 "In12.Cu" signal "L13GND")
		(2 "B.Cu" signal "BOTTOM")
		(9 "F.Adhes" user "F.Adhesive")
		(11 "B.Adhes" user "B.Adhesive")
		(13 "F.Paste" user "Package Geometry/Pastemask Top")
		(15 "B.Paste" user "Package Geometry/Pastemask Bottom")
		(5 "F.SilkS" user "Ref Des/Silkscreen Top")
		(7 "B.SilkS" user "Ref Des/Silkscreen Bottom")
		(1 "F.Mask" user "Board Geometry/Soldermask Top")
		(3 "B.Mask" user "Board Geometry/Soldermask Bottom")
		(17 "Dwgs.User" user "User.Drawings")
		(19 "Cmts.User" user "User.Comments")
		(21 "Eco1.User" user "User.Eco1")
		(23 "Eco2.User" user "User.Eco2")
		(25 "Edge.Cuts" user "Board Geometry/Outline")
		(27 "Margin" user)
		(31 "F.CrtYd" user "Package Geometry/Place Bound Top")
		(29 "B.CrtYd" user "Package Geometry/Place Bound Bottom")
		(35 "F.Fab" user "Ref Des/Assembly Top")
		(33 "B.Fab" user "Ref Des/Assembly Bottom")
	)
	(footprint ""
		(layer "B.Cu")
		(at 350.024192 -77.834236 180)
		(property "Reference" "C3P27"
			(at 0 0 0)
			(layer "B.SilkS")
			(hide yes)
			(effects
				(font
					(size 1.27 1.27)
				)
				(justify mirror)
			)
		)
		(property "Value" ""
			(at 0 0 0)
			(layer "B.Fab")
			(effects
				(font
					(size 1.27 1.27)
				)
				(justify mirror)
			)
		)
		(duplicate_pad_numbers_are_jumpers no)
		(fp_poly
			(pts
				(xy -0.3048 -0.1016) (xy -0.3048 0.9906) (xy 0.3048 0.9906) (xy 0.3048 -0.1016)
			)
			(stroke
				(width 0)
				(type default)
			)
			(fill no)
			(layer "B.CrtYd")
		)
		(fp_line
			(start 0.3048 0.9906)
			(end -0.3048 0.9906)
			(stroke
				(width 0.1)
				(type default)
			)
			(layer "B.Fab")
		)
		(fp_line
			(start 0.3048 -0.1016)
			(end 0.3048 0.9906)
			(stroke
				(width 0.1)
				(type default)
			)
			(layer "B.Fab")
		)
		(fp_line
			(start -0.3048 0.9906)
			(end -0.3048 -0.1016)
			(stroke
				(width 0.1)
				(type default)
			)
			(layer "B.Fab")
		)
		(fp_line
			(start -0.3048 -0.1016)
			(end 0.3048 -0.1016)
			(stroke
				(width 0.1)
				(type default)
			)
			(layer "B.Fab")
		)
		(pad "1" smd rect
			(at 0 0)
			(size 0.508 0.508)
			(layers "B.Cu" "B.Mask" "B.Paste")
			(net "P3E_CPU0_PE1_SS_TXP<4>")
		)
		(pad "2" smd rect
			(at 0 0.889)
			(size 0.508 0.508)
			(layers "B.Cu" "B.Mask" "B.Paste")
			(net "P3E_CPU0_PE1_PCH_TXP<4>")
		)
		(zone
			(layer "B.Cu")
			(hatch none 0.5)
			(connect_pads
				(clearance 0)
			)
			(min_thickness 0.25)
			(keepout
				(tracks not_allowed)
				(vias allowed)
				(pads allowed)
				(copperpour not_allowed)
				(footprints allowed)
			)
			(placement
				(enabled no)
				(sheetname "")
			)
			(fill
				(thermal_gap 0.5)
				(thermal_bridge_width 0.5)
				(island_removal_mode 0)
			)
			(polygon
				(pts
					(xy 349.770192 -78.469236) (xy 350.278192 -78.469236) (xy 350.278192 -78.088236) (xy 349.770192 -78.088236)
				)
			)
		)
		(zone
			(layer "B.Cu")
			(hatch none 0.5)
			(connect_pads
				(clearance 0)
			)
			(min_thickness 0.25)
			(keepout
				(tracks allowed)
				(vias not_allowed)
				(pads allowed)
				(copperpour not_allowed)
				(footprints allowed)
			)
			(placement
				(enabled no)
				(sheetname "")
			)
			(fill
				(thermal_gap 0.5)
				(thermal_bridge_width 0.5)
				(island_removal_mode 0)
			)
			(polygon
				(pts
					(xy 349.770192 -78.088236) (xy 350.278192 -78.088236) (xy 350.278192 -78.469236) (xy 349.770192 -78.469236)
				)
			)
		)
	)
	(footprint ""
		(layer "B.Cu")
		(at 396.06982 -139.69238 180)
		(property "Reference" "C2L46"
			(at -3.10007 3.24612 270)
			(unlocked yes)
			(layer "B.SilkS")
			(effects
				(font
					(size 0.7874 0.5842)
					(thickness 0.1524)
				)
				(justify mirror)
			)
		)
		(property "Value" ""
			(at 0 0 0)
			(layer "B.Fab")
			(effects
				(font
					(size 1.27 1.27)
				)
				(justify mirror)
			)
		)
		(duplicate_pad_numbers_are_jumpers no)
		(fp_line
			(start 2.563114 1.633728)
			(end 1.6002 1.633728)
			(stroke
				(width 0.1524)
				(type default)
			)
			(layer "B.SilkS")
		)
		(fp_line
			(start 2.563114 -1.616456)
			(end 2.563114 1.633728)
			(stroke
				(width 0.1524)
				(type default)
			)
			(layer "B.SilkS")
		)
		(fp_line
			(start 2.286 7.366)
			(end 2.286 1.632712)
			(stroke
				(width 0.1524)
				(type default)
			)
			(layer "B.SilkS")
		)
		(fp_line
			(start 2.286 7.366)
			(end 1.60147 7.366)
			(stroke
				(width 0.1524)
				(type default)
			)
			(layer "B.SilkS")
		)
		(fp_line
			(start 1.6002 -1.616456)
			(end 2.563114 -1.616456)
			(stroke
				(width 0.1524)
				(type default)
			)
			(layer "B.SilkS")
		)
		(fp_line
			(start -1.6002 -1.616456)
			(end -2.504948 -1.616456)
			(stroke
				(width 0.1524)
				(type default)
			)
			(layer "B.SilkS")
		)
		(fp_line
			(start -2.286 7.366)
			(end -1.600708 7.366)
			(stroke
				(width 0.1524)
				(type default)
			)
			(layer "B.SilkS")
		)
		(fp_line
			(start -2.286 7.366)
			(end -2.286 1.63195)
			(stroke
				(width 0.1524)
				(type default)
			)
			(layer "B.SilkS")
		)
		(fp_line
			(start -2.504948 1.633728)
			(end -1.6002 1.633728)
			(stroke
				(width 0.1524)
				(type default)
			)
			(layer "B.SilkS")
		)
		(fp_line
			(start -2.504948 -1.616456)
			(end -2.504948 1.633728)
			(stroke
				(width 0.1524)
				(type default)
			)
			(layer "B.SilkS")
		)
		(fp_rect
			(start 2.286 7.366)
			(end -2.286 -0.254)
			(stroke
				(width 0)
				(type default)
			)
			(fill no)
			(layer "B.CrtYd")
		)
		(fp_line
			(start 2.286 7.366)
			(end 2.286 -0.254)
			(stroke
				(width 0.1)
				(type default)
			)
			(layer "B.Fab")
		)
		(fp_line
			(start 2.286 -0.254)
			(end -2.286 -0.254)
			(stroke
				(width 0.1)
				(type default)
			)
			(layer "B.Fab")
		)
		(fp_line
			(start -2.286 7.366)
			(end 2.286 7.366)
			(stroke
				(width 0.1)
				(type default)
			)
			(layer "B.Fab")
		)
		(fp_line
			(start -2.286 -0.254)
			(end -2.286 7.366)
			(stroke
				(width 0.1)
				(type default)
			)
			(layer "B.Fab")
		)
		(pad "1" smd rect
			(at 0 0)
			(size 2.54 3.048)
			(layers "B.Cu" "B.Mask" "B.Paste")
			(net "P1V05_PCH_STBY")
		)
		(pad "2" smd rect
			(at 0 7.112)
			(size 2.54 3.048)
			(layers "B.Cu" "B.Mask" "B.Paste")
			(net "GND")
		)
	)
	(footprint ""
		(layer "B.Cu")
		(at 488.191302 -46.854872 -90)
		(property "Reference" "C9E1"
			(at 0 0 90)
			(layer "B.SilkS")
			(hide yes)
			(effects
				(font
					(size 1.27 1.27)
				)
				(justify mirror)
			)
		)
		(property "Value" ""
			(at 0 0 90)
			(layer "B.Fab")
			(effects
				(font
					(size 1.27 1.27)
				)
				(justify mirror)
			)
		)
		(duplicate_pad_numbers_are_jumpers no)
		(fp_poly
			(pts
				(xy 0.4953 -0.2032) (xy -0.4953 -0.2032) (xy -0.4953 1.6002) (xy 0.4953 1.6002)
			)
			(stroke
				(width 0)
				(type default)
			)
			(fill no)
			(layer "B.CrtYd")
		)
		(fp_line
			(start -0.4953 1.6002)
			(end 0.4953 1.6002)
			(stroke
				(width 0.1)
				(type default)
			)
			(layer "B.Fab")
		)
		(fp_line
			(start 0.4953 1.6002)
			(end 0.4953 -0.2032)
			(stroke
				(width 0.1)
				(type default)
			)
			(layer "B.Fab")
		)
		(fp_line
			(start -0.4953 -0.2032)
			(end -0.4953 1.6002)
			(stroke
				(width 0.1)
				(type default)
			)
			(layer "B.Fab")
		)
		(fp_line
			(start 0.4953 -0.2032)
			(end -0.4953 -0.2032)
			(stroke
				(width 0.1)
				(type default)
			)
			(layer "B.Fab")
		)
		(pad "1" smd rect
			(at 0 0 90)
			(size 0.762 0.889)
			(layers "B.Cu" "B.Mask" "B.Paste")
			(net "P0V9_LAN")
		)
		(pad "2" smd rect
			(at 0 1.397 90)
			(size 0.762 0.889)
			(layers "B.Cu" "B.Mask" "B.Paste")
			(net "GND")
		)
		(zone
			(layer "B.Cu")
			(hatch none 0.5)
			(connect_pads
				(clearance 0)
			)
			(min_thickness 0.25)
			(keepout
				(tracks not_allowed)
				(vias allowed)
				(pads allowed)
				(copperpour not_allowed)
				(footprints allowed)
			)
			(placement
				(enabled no)
				(sheetname "")
			)
			(fill
				(thermal_gap 0.5)
				(thermal_bridge_width 0.5)
				(island_removal_mode 0)
			)
			(polygon
				(pts
					(xy 487.746802 -46.473872) (xy 487.746802 -47.235872) (xy 487.238802 -47.235872) (xy 487.238802 -46.473872)
				)
			)
		)
	)
	(footprint ""
		(layer "B.Cu")
		(at 94.460568 -17.5514 90)
		(property "Reference" "C8U1"
			(at 0 0 90)
			(layer "B.SilkS")
			(hide yes)
			(effects
				(font
					(size 1.27 1.27)
				)
				(justify mirror)
			)
		)
		(property "Value" ""
			(at 0 0 90)
			(layer "B.Fab")
			(effects
				(font
					(size 1.27 1.27)
				)
				(justify mirror)
			)
		)
		(duplicate_pad_numbers_are_jumpers no)
		(fp_poly
			(pts
				(xy 0.7239 -0.2159) (xy -0.7239 -0.2159) (xy -0.7239 1.9939) (xy 0.7239 1.9939)
			)
			(stroke
				(width 0)
				(type default)
			)
			(fill no)
			(layer "B.CrtYd")
		)
		(fp_line
			(start 0.7239 -0.2159)
			(end 0.7239 1.9939)
			(stroke
				(width 0.1)
				(type default)
			)
			(layer "B.Fab")
		)
		(fp_line
			(start -0.7239 -0.2159)
			(end 0.7239 -0.2159)
			(stroke
				(width 0.1)
				(type default)
			)
			(layer "B.Fab")
		)
		(fp_line
			(start 0.7239 1.9939)
			(end -0.7239 1.9939)
			(stroke
				(width 0.1)
				(type default)
			)
			(layer "B.Fab")
		)
		(fp_line
			(start -0.7239 1.9939)
			(end -0.7239 -0.2159)
			(stroke
				(width 0.1)
				(type default)
			)
			(layer "B.Fab")
		)
		(pad "1" smd rect
			(at 0 0 270)
			(size 1.27 1.016)
			(layers "B.Cu" "B.Mask" "B.Paste")
			(net "PVDDQ_GHJ")
		)
		(pad "2" smd rect
			(at 0 1.778 270)
			(size 1.27 1.016)
			(layers "B.Cu" "B.Mask" "B.Paste")
			(net "GND")
		)
		(zone
			(layer "B.Cu")
			(hatch none 0.5)
			(connect_pads
				(clearance 0)
			)
			(min_thickness 0.25)
			(keepout
				(tracks not_allowed)
				(vias allowed)
				(pads allowed)
				(copperpour not_allowed)
				(footprints allowed)
			)
			(placement
				(enabled no)
				(sheetname "")
			)
			(fill
				(thermal_gap 0.5)
				(thermal_bridge_width 0.5)
				(island_removal_mode 0)
			)
			(polygon
				(pts
					(xy 94.968568 -18.1864) (xy 94.968568 -16.9164) (xy 95.730568 -16.9164) (xy 95.730568 -18.1864)
				)
			)
		)
	)
	(footprint ""
		(layer "B.Cu")
		(at 497.561108 -41.41343)
		(property "Reference" "C25P80"
			(at 0.8382 -0.67818 0)
			(unlocked yes)
			(layer "B.SilkS")
			(effects
				(font
					(size 0.4064 0.254)
					(thickness 0.1524)
				)
				(justify left mirror)
			)
		)
		(property "Value" ""
			(at 0 0 0)
			(layer "B.Fab")
			(effects
				(font
					(size 1.27 1.27)
				)
				(justify mirror)
			)
		)
		(duplicate_pad_numbers_are_jumpers no)
		(fp_poly
			(pts
				(xy -0.3048 -0.1016) (xy -0.3048 0.9906) (xy 0.3048 0.9906) (xy 0.3048 -0.1016)
			)
			(stroke
				(width 0)
				(type default)
			)
			(fill no)
			(layer "B.CrtYd")
		)
		(fp_line
			(start -0.3048 -0.1016)
			(end 0.3048 -0.1016)
			(stroke
				(width 0.1)
				(type default)
			)
			(layer "B.Fab")
		)
		(fp_line
			(start -0.3048 0.9906)
			(end -0.3048 -0.1016)
			(stroke
				(width 0.1)
				(type default)
			)
			(layer "B.Fab")
		)
		(fp_line
			(start 0.3048 -0.1016)
			(end 0.3048 0.9906)
			(stroke
				(width 0.1)
				(type default)
			)
			(layer "B.Fab")
		)
		(fp_line
			(start 0.3048 0.9906)
			(end -0.3048 0.9906)
			(stroke
				(width 0.1)
				(type default)
			)
			(layer "B.Fab")
		)
		(pad "1" smd rect
			(at 0 0 180)
			(size 0.508 0.508)
			(layers "B.Cu" "B.Mask" "B.Paste")
			(net "P5V_VGA_D")
		)
		(pad "2" smd rect
			(at 0 0.889 180)
			(size 0.508 0.508)
			(layers "B.Cu" "B.Mask" "B.Paste")
			(net "GND")
		)
		(zone
			(layer "B.Cu")
			(hatch none 0.5)
			(connect_pads
				(clearance 0)
			)
			(min_thickness 0.25)
			(keepout
				(tracks allowed)
				(vias not_allowed)
				(pads allowed)
				(copperpour not_allowed)
				(footprints allowed)
			)
			(placement
				(enabled no)
				(sheetname "")
			)
			(fill
				(thermal_gap 0.5)
				(thermal_bridge_width 0.5)
				(island_removal_mode 0)
			)
			(polygon
				(pts
					(xy 497.815108 -41.15943) (xy 497.307108 -41.15943) (xy 497.307108 -40.77843) (xy 497.815108 -40.77843)
				)
			)
		)
		(zone
			(layer "B.Cu")
			(hatch none 0.5)
			(connect_pads
				(clearance 0)
			)
			(min_thickness 0.25)
			(keepout
				(tracks not_allowed)
				(vias allowed)
				(pads allowed)
				(copperpour not_allowed)
				(footprints allowed)
			)
			(placement
				(enabled no)
				(sheetname "")
			)
			(fill
				(thermal_gap 0.5)
				(thermal_bridge_width 0.5)
				(island_removal_mode 0)
			)
			(polygon
				(pts
					(xy 497.815108 -40.77843) (xy 497.307108 -40.77843) (xy 497.307108 -41.15943) (xy 497.815108 -41.15943)
				)
			)
		)
	)
	(footprint ""
		(layer "B.Cu")
		(at 405.84882 -52.19192 90)
		(property "Reference" "R1W3"
			(at 0 0 90)
			(layer "B.SilkS")
			(hide yes)
			(effects
				(font
					(size 1.27 1.27)
				)
				(justify mirror)
			)
		)
		(property "Value" "*"
			(at -0.064008 -4.108196 90)
			(unlocked yes)
			(layer "B.Fab")
			(hide yes)
			(effects
				(font
					(size 1.27 1.016)
					(thickness 0.1524)
				)
				(justify mirror)
			)
		)
		(property "Device Type" "1MR2F-L-GP_SMD-RG1-1MR2F-L-GP,A"
			(at -0.064008 -5.632196 90)
			(unlocked yes)
			(layer "B.Fab")
			(hide yes)
			(effects
				(font
					(size 1.27 1.016)
					(thickness 0.1524)
				)
				(justify mirror)
			)
		)
		(duplicate_pad_numbers_are_jumpers no)
		(fp_line
			(start 0.508 -0.9398)
			(end 0.508 0.9398)
			(stroke
				(width 0.1524)
				(type default)
			)
			(layer "B.SilkS")
		)
		(fp_line
			(start -0.508 -0.9398)
			(end 0.508 -0.9398)
			(stroke
				(width 0.1524)
				(type default)
			)
			(layer "B.SilkS")
		)
		(fp_rect
			(start 0.508 0.9398)
			(end -0.508 -0.9398)
			(stroke
				(width 0)
				(type default)
			)
			(fill no)
			(layer "B.CrtYd")
		)
		(fp_rect
			(start 0.508 0.9398)
			(end -0.508 -0.9398)
			(stroke
				(width 0)
				(type default)
			)
			(fill no)
			(layer "B.Fab")
		)
		(pad "1" smd custom
			(at 0 -0.4445 270)
			(size 0.1397 0.1397)
			(layers "B.Cu" "B.Mask" "B.Paste")
			(net "P3V3_STBY")
			(options
				(clearance outline)
				(anchor circle)
			)
			(primitives
				(gr_poly
					(pts
						(arc
							(start -0.1778 0.2794)
							(mid -0.249642 0.249642)
							(end -0.2794 0.1778)
						)
						(arc
							(start -0.2794 -0.1778)
							(mid -0.249642 -0.249642)
							(end -0.1778 -0.2794)
						)
						(arc
							(start 0.1778 -0.2794)
							(mid 0.249642 -0.249642)
							(end 0.2794 -0.1778)
						)
						(arc
							(start 0.2794 0.1778)
							(mid 0.249642 0.249642)
							(end 0.1778 0.2794)
						)
					)
					(width 0)
					(fill yes)
				)
			)
		)
		(pad "2" smd custom
			(at 0 0.4445 270)
			(size 0.1397 0.1397)
			(layers "B.Cu" "B.Mask" "B.Paste")
			(net "FM_OCP_MEZZB_PRES_N")
			(options
				(clearance outline)
				(anchor circle)
			)
			(primitives
				(gr_poly
					(pts
						(arc
							(start -0.1778 0.2794)
							(mid -0.249642 0.249642)
							(end -0.2794 0.1778)
						)
						(arc
							(start -0.2794 -0.1778)
							(mid -0.249642 -0.249642)
							(end -0.1778 -0.2794)
						)
						(arc
							(start 0.1778 -0.2794)
							(mid 0.249642 -0.249642)
							(end 0.2794 -0.1778)
						)
						(arc
							(start 0.2794 0.1778)
							(mid 0.249642 0.249642)
							(end 0.1778 0.2794)
						)
					)
					(width 0)
					(fill yes)
				)
			)
		)
	)
	(footprint ""
		(layer "B.Cu")
		(at 470.027 -58.674 -90)
		(property "Reference" "R1W45"
			(at 0.8382 -0.67818 270)
			(unlocked yes)
			(layer "B.SilkS")
			(effects
				(font
					(size 0.4064 0.254)
					(thickness 0.1524)
				)
				(justify left mirror)
			)
		)
		(property "Value" ""
			(at 0 0 90)
			(layer "B.Fab")
			(effects
				(font
					(size 1.27 1.27)
				)
				(justify mirror)
			)
		)
		(duplicate_pad_numbers_are_jumpers no)
		(fp_poly
			(pts
				(xy 0.2794 -0.1016) (xy -0.2794 -0.1016) (xy -0.2794 0.9906) (xy 0.2794 0.9906)
			)
			(stroke
				(width 0)
				(type default)
			)
			(fill no)
			(layer "B.CrtYd")
		)
		(fp_line
			(start -0.2794 0.9906)
			(end -0.2794 -0.1016)
			(stroke
				(width 0.1)
				(type default)
			)
			(layer "B.Fab")
		)
		(fp_line
			(start 0.2794 0.9906)
			(end -0.2794 0.9906)
			(stroke
				(width 0.1)
				(type default)
			)
			(layer "B.Fab")
		)
		(fp_line
			(start -0.2794 -0.1016)
			(end 0.2794 -0.1016)
			(stroke
				(width 0.1)
				(type default)
			)
			(layer "B.Fab")
		)
		(fp_line
			(start 0.2794 -0.1016)
			(end 0.2794 0.9906)
			(stroke
				(width 0.1)
				(type default)
			)
			(layer "B.Fab")
		)
		(pad "1" smd rect
			(at 0 0 90)
			(size 0.508 0.508)
			(layers "B.Cu" "B.Mask" "B.Paste")
			(net "P3V3_STBY")
		)
		(pad "2" smd rect
			(at 0 0.889 90)
			(size 0.508 0.508)
			(layers "B.Cu" "B.Mask" "B.Paste")
			(net "FM_GBE3_LVC3_MOD_ABS")
		)
		(zone
			(layer "B.Cu")
			(hatch none 0.5)
			(connect_pads
				(clearance 0)
			)
			(min_thickness 0.25)
			(keepout
				(tracks not_allowed)
				(vias allowed)
				(pads allowed)
				(copperpour not_allowed)
				(footprints allowed)
			)
			(placement
				(enabled no)
				(sheetname "")
			)
			(fill
				(thermal_gap 0.5)
				(thermal_bridge_width 0.5)
				(island_removal_mode 0)
			)
			(polygon
				(pts
					(xy 469.392 -58.42) (xy 469.392 -58.928) (xy 469.773 -58.928) (xy 469.773 -58.42)
				)
			)
		)
		(zone
			(layer "B.Cu")
			(hatch none 0.5)
			(connect_pads
				(clearance 0)
			)
			(min_thickness 0.25)
			(keepout
				(tracks allowed)
				(vias not_allowed)
				(pads allowed)
				(copperpour not_allowed)
				(footprints allowed)
			)
			(placement
				(enabled no)
				(sheetname "")
			)
			(fill
				(thermal_gap 0.5)
				(thermal_bridge_width 0.5)
				(island_removal_mode 0)
			)
			(polygon
				(pts
					(xy 469.773 -58.42) (xy 469.773 -58.928) (xy 469.392 -58.928) (xy 469.392 -58.42)
				)
			)
		)
	)
	(footprint ""
		(layer "B.Cu")
		(at 97.206054 -77.82814)
		(property "Reference" "C8P19"
			(at 0 0 0)
			(layer "B.SilkS")
			(hide yes)
			(effects
				(font
					(size 1.27 1.27)
				)
				(justify mirror)
			)
		)
		(property "Value" ""
			(at 0 0 0)
			(layer "B.Fab")
			(effects
				(font
					(size 1.27 1.27)
				)
				(justify mirror)
			)
		)
		(duplicate_pad_numbers_are_jumpers no)
		(fp_poly
			(pts
				(xy 0.7239 -0.2159) (xy -0.7239 -0.2159) (xy -0.7239 1.9939) (xy 0.7239 1.9939)
			)
			(stroke
				(width 0)
				(type default)
			)
			(fill no)
			(layer "B.CrtYd")
		)
		(fp_line
			(start -0.7239 -0.2159)
			(end 0.7239 -0.2159)
			(stroke
				(width 0.1)
				(type default)
			)
			(layer "B.Fab")
		)
		(fp_line
			(start -0.7239 1.9939)
			(end -0.7239 -0.2159)
			(stroke
				(width 0.1)
				(type default)
			)
			(layer "B.Fab")
		)
		(fp_line
			(start 0.7239 -0.2159)
			(end 0.7239 1.9939)
			(stroke
				(width 0.1)
				(type default)
			)
			(layer "B.Fab")
		)
		(fp_line
			(start 0.7239 1.9939)
			(end -0.7239 1.9939)
			(stroke
				(width 0.1)
				(type default)
			)
			(layer "B.Fab")
		)
		(pad "1" smd rect
			(at 0 0 180)
			(size 1.27 1.016)
			(layers "B.Cu" "B.Mask" "B.Paste")
			(net "PVCCIN_CPU1")
		)
		(pad "2" smd rect
			(at 0 1.778 180)
			(size 1.27 1.016)
			(layers "B.Cu" "B.Mask" "B.Paste")
			(net "GND")
		)
		(zone
			(layer "B.Cu")
			(hatch none 0.5)
			(connect_pads
				(clearance 0)
			)
			(min_thickness 0.25)
			(keepout
				(tracks not_allowed)
				(vias allowed)
				(pads allowed)
				(copperpour not_allowed)
				(footprints allowed)
			)
			(placement
				(enabled no)
				(sheetname "")
			)
			(fill
				(thermal_gap 0.5)
				(thermal_bridge_width 0.5)
				(island_removal_mode 0)
			)
			(polygon
				(pts
					(xy 97.841054 -77.32014) (xy 96.571054 -77.32014) (xy 96.571054 -76.55814) (xy 97.841054 -76.55814)
				)
			)
		)
	)
)
